# S9S_MB_2U (Grand Teton) — schematic netlist excerpt (pin names and nets, part order shuffled) for the footprints in the layout excerpt that follows; sources: Cadence DE-HDL packaged netlist, KiCad conversion of 03242023_DA0F0TMBIJ0_F0T_Motherboard_J_brd_V01_OCP.brd

PC226  Q_CAP  2.2UF 10V 10% X6S  pkg C0402  page 270 : A = PVCCIN_CPU0_VDD8 ; B = GND
R3298  Q_RES  10K 1% CHIP  pkg 0402LF  page 190 : A = P3V3_AUX ; B = HDD_ACTIVITY_BUF_N

(kicad_pcb
	(version 20260206)
	(generator "pcbnew")
	(generator_version "10.0")
	(general
		(thickness 1.6)
		(legacy_teardrops no)
	)
	(paper "A4")
	(title_block
		(title "03242023_DA0F0TMBIJ0_F0T_Motherboard_J_brd_V01_OCP.brd")
		(comment 1 "Grand Teton / footprints 448-449 of 6105")
	)
	(layers
		(0 "F.Cu" signal "TOP")
		(4 "In1.Cu" signal "GND")
		(6 "In2.Cu" signal "IN1")
		(8 "In3.Cu" signal "GND1")
		(10 "In4.Cu" signal "IN2")
		(12 "In5.Cu" signal "GND2")
		(14 "In6.Cu" signal "IN3")
		(16 "In7.Cu" signal "GND3")
		(18 "In8.Cu" signal "VCC")
		(20 "In9.Cu" signal "VCC1")
		(22 "In10.Cu" signal "GND4")
		(24 "In11.Cu" signal "IN4")
		(26 "In12.Cu" signal "GND5")
		(28 "In13.Cu" signal "IN5")
		(30 "In14.Cu" signal "GND6")
		(32 "In15.Cu" signal "IN6")
		(34 "In16.Cu" signal "GND7")
		(2 "B.Cu" signal "BOTTOM")
		(9 "F.Adhes" user "F.Adhesive")
		(11 "B.Adhes" user "B.Adhesive")
		(13 "F.Paste" user "Package Geometry/Pastemask Top")
		(15 "B.Paste" user "Package Geometry/Pastemask Bottom")
		(5 "F.SilkS" user "Ref Des/Silkscreen Top")
		(7 "B.SilkS" user "Ref Des/Silkscreen Bottom")
		(1 "F.Mask" user "Board Geometry/Soldermask Top")
		(3 "B.Mask" user "Board Geometry/Soldermask Bottom")
		(17 "Dwgs.User" user "User.Drawings")
		(19 "Cmts.User" user "User.Comments")
		(21 "Eco1.User" user "User.Eco1")
		(23 "Eco2.User" user "User.Eco2")
		(25 "Edge.Cuts" user "Board Geometry/Outline")
		(27 "Margin" user)
		(31 "F.CrtYd" user "Package Geometry/Place Bound Top")
		(29 "B.CrtYd" user "Package Geometry/Place Bound Bottom")
		(35 "F.Fab" user "Ref Des/Assembly Top")
		(33 "B.Fab" user "Ref Des/Assembly Bottom")
	)
	(footprint ""
		(layer "F.Cu")
		(at 140.00988 -46.954948 180)
		(property "Reference" "R3298"
			(at 0 0 180)
			(layer "F.SilkS")
			(hide yes)
			(effects
				(font
					(size 1.27 1.27)
				)
			)
		)
		(property "Value" ""
			(at 0 0 180)
			(layer "F.Fab")
			(effects
				(font
					(size 1.27 1.27)
				)
			)
		)
		(duplicate_pad_numbers_are_jumpers no)
		(fp_line
			(start 0.7874 0.4064)
			(end -0.7874 0.4064)
			(stroke
				(width 0.1524)
				(type default)
			)
			(layer "F.SilkS")
		)
		(fp_line
			(start 0.7874 -0.4064)
			(end 0.7874 0.4064)
			(stroke
				(width 0.1524)
				(type default)
			)
			(layer "F.SilkS")
		)
		(fp_line
			(start -0.7874 0.4064)
			(end -0.7874 -0.4064)
			(stroke
				(width 0.1524)
				(type default)
			)
			(layer "F.SilkS")
		)
		(fp_line
			(start -0.7874 -0.4064)
			(end 0.7874 -0.4064)
			(stroke
				(width 0.1524)
				(type default)
			)
			(layer "F.SilkS")
		)
		(fp_line
			(start 0.67945 0.3048)
			(end 0.120396 0.3048)
			(stroke
				(width 0.1)
				(type default)
			)
			(layer "F.Fab")
		)
		(fp_line
			(start 0.67945 -0.3048)
			(end 0.67945 0.3048)
			(stroke
				(width 0.1)
				(type default)
			)
			(layer "F.Fab")
		)
		(fp_line
			(start 0.12065 -0.2794)
			(end 0.12065 -0.3048)
			(stroke
				(width 0.1)
				(type default)
			)
			(layer "F.Fab")
		)
		(fp_line
			(start 0.12065 -0.3048)
			(end 0.67945 -0.3048)
			(stroke
				(width 0.1)
				(type default)
			)
			(layer "F.Fab")
		)
		(fp_line
			(start 0.120396 0.3048)
			(end 0.120396 0.2794)
			(stroke
				(width 0.1)
				(type default)
			)
			(layer "F.Fab")
		)
		(fp_line
			(start 0.120396 0.2794)
			(end -0.12065 0.2794)
			(stroke
				(width 0.1)
				(type default)
			)
			(layer "F.Fab")
		)
		(fp_line
			(start -0.12065 0.3048)
			(end -0.67945 0.3048)
			(stroke
				(width 0.1)
				(type default)
			)
			(layer "F.Fab")
		)
		(fp_line
			(start -0.12065 0.2794)
			(end -0.12065 0.3048)
			(stroke
				(width 0.1)
				(type default)
			)
			(layer "F.Fab")
		)
		(fp_line
			(start -0.12065 -0.2794)
			(end 0.12065 -0.2794)
			(stroke
				(width 0.1)
				(type default)
			)
			(layer "F.Fab")
		)
		(fp_line
			(start -0.12065 -0.305054)
			(end -0.12065 -0.2794)
			(stroke
				(width 0.1)
				(type default)
			)
			(layer "F.Fab")
		)
		(fp_line
			(start -0.67945 0.3048)
			(end -0.67945 -0.305054)
			(stroke
				(width 0.1)
				(type default)
			)
			(layer "F.Fab")
		)
		(fp_line
			(start -0.67945 -0.305054)
			(end -0.12065 -0.305054)
			(stroke
				(width 0.1)
				(type default)
			)
			(layer "F.Fab")
		)
		(pad "1" smd circle
			(at -0.40005 0 180)
			(size 0 0)
			(layers "F.Cu" "F.Mask" "F.Paste")
			(net "P3V3_AUX")
		)
		(pad "2" smd circle
			(at 0.40005 0 180)
			(size 0 0)
			(layers "F.Cu" "F.Mask" "F.Paste")
			(net "HDD_ACTIVITY_BUF_N")
		)
	)
	(footprint ""
		(layer "F.Cu")
		(at 382.165352 -345.393264 90)
		(property "Reference" "PC226"
			(at 0 0 90)
			(layer "F.SilkS")
			(hide yes)
			(effects
				(font
					(size 1.27 1.27)
				)
			)
		)
		(property "Value" ""
			(at 0 0 90)
			(layer "F.Fab")
			(effects
				(font
					(size 1.27 1.27)
				)
			)
		)
		(duplicate_pad_numbers_are_jumpers no)
		(fp_line
			(start 0.7874 -0.4064)
			(end 0.7874 0.4064)
			(stroke
				(width 0.1524)
				(type default)
			)
			(layer "F.SilkS")
		)
		(fp_line
			(start -0.7874 -0.4064)
			(end 0.7874 -0.4064)
			(stroke
				(width 0.1524)
				(type default)
			)
			(layer "F.SilkS")
		)
		(fp_line
			(start 0.7874 0.4064)
			(end -0.7874 0.4064)
			(stroke
				(width 0.1524)
				(type default)
			)
			(layer "F.SilkS")
		)
		(fp_line
			(start -0.7874 0.4064)
			(end -0.7874 -0.4064)
			(stroke
				(width 0.1524)
				(type default)
			)
			(layer "F.SilkS")
		)
		(fp_line
			(start -0.12065 -0.305054)
			(end -0.12065 -0.2794)
			(stroke
				(width 0.1)
				(type default)
			)
			(layer "F.Fab")
		)
		(fp_line
			(start -0.67945 -0.305054)
			(end -0.12065 -0.305054)
			(stroke
				(width 0.1)
				(type default)
			)
			(layer "F.Fab")
		)
		(fp_line
			(start 0.67945 -0.3048)
			(end 0.67945 0.3048)
			(stroke
				(width 0.1)
				(type default)
			)
			(layer "F.Fab")
		)
		(fp_line
			(start 0.12065 -0.3048)
			(end 0.67945 -0.3048)
			(stroke
				(width 0.1)
				(type default)
			)
			(layer "F.Fab")
		)
		(fp_line
			(start 0.12065 -0.2794)
			(end 0.12065 -0.3048)
			(stroke
				(width 0.1)
				(type default)
			)
			(layer "F.Fab")
		)
		(fp_line
			(start -0.12065 -0.2794)
			(end 0.12065 -0.2794)
			(stroke
				(width 0.1)
				(type default)
			)
			(layer "F.Fab")
		)
		(fp_line
			(start 0.120396 0.2794)
			(end -0.12065 0.2794)
			(stroke
				(width 0.1)
				(type default)
			)
			(layer "F.Fab")
		)
		(fp_line
			(start -0.12065 0.2794)
			(end -0.12065 0.3048)
			(stroke
				(width 0.1)
				(type default)
			)
			(layer "F.Fab")
		)
		(fp_line
			(start 0.67945 0.3048)
			(end 0.120396 0.3048)
			(stroke
				(width 0.1)
				(type default)
			)
			(layer "F.Fab")
		)
		(fp_line
			(start 0.120396 0.3048)
			(end 0.120396 0.2794)
			(stroke
				(width 0.1)
				(type default)
			)
			(layer "F.Fab")
		)
		(fp_line
			(start -0.12065 0.3048)
			(end -0.67945 0.3048)
			(stroke
				(width 0.1)
				(type default)
			)
			(layer "F.Fab")
		)
		(fp_line
			(start -0.67945 0.3048)
			(end -0.67945 -0.305054)
			(stroke
				(width 0.1)
				(type default)
			)
			(layer "F.Fab")
		)
		(pad "1" smd circle
			(at -0.40005 0 90)
			(size 0 0)
			(layers "F.Cu" "F.Mask" "F.Paste")
			(net "PVCCIN_CPU0_VDD8")
		)
		(pad "2" smd circle
			(at 0.40005 0 90)
			(size 0 0)
			(layers "F.Cu" "F.Mask" "F.Paste")
			(net "GND")
		)
	)
)
